(kicad_pcb
	(version 20241229)
	(generator "pcbnew")
	(generator_version "9.0")
	(general
		(thickness 1.61)
		(legacy_teardrops no)
	)
	(paper "A3")
	(title_block
		(title "SO-DIMM DDR5 Tester")
		(date "2025-11-26")
		(rev "1.3.0")
		(comment 9 "footprints 176-179 of 627")
	)
	(layers
		(0 "F.Cu" signal)
		(4 "In1.Cu" power)
		(6 "In2.Cu" mixed)
		(8 "In3.Cu" power)
		(10 "In4.Cu" mixed)
		(12 "In5.Cu" power)
		(14 "In6.Cu" mixed)
		(16 "In7.Cu" power)
		(18 "In8.Cu" power)
		(20 "In9.Cu" mixed)
		(22 "In10.Cu" power)
		(2 "B.Cu" signal)
		(9 "F.Adhes" user "F.Adhesive")
		(11 "B.Adhes" user "B.Adhesive")
		(13 "F.Paste" user)
		(15 "B.Paste" user)
		(5 "F.SilkS" user "F.Silkscreen")
		(7 "B.SilkS" user "B.Silkscreen")
		(1 "F.Mask" user)
		(3 "B.Mask" user)
		(17 "Dwgs.User" user "User.Drawings")
		(19 "Cmts.User" user "User.Comments")
		(21 "Eco1.User" user "User.Eco1")
		(23 "Eco2.User" user "User.Eco2")
		(25 "Edge.Cuts" user)
		(27 "Margin" user)
		(31 "F.CrtYd" user "F.Courtyard")
		(29 "B.CrtYd" user "B.Courtyard")
		(35 "F.Fab" user)
		(33 "B.Fab" user)
	)
	(footprint "antmicro-footprints:DHVQFN-14-1EP_2.5x3mm"
		(layer "F.Cu")
		(at 104.651 181.685 -90)
		(property "Reference" "U13"
			(at 1.915 4.151 0)
			(layer "F.SilkS")
			(effects
				(font
					(size 0.7 0.7)
					(thickness 0.15)
				)
				(justify left bottom)
			)
		)
		(property "Value" "TXU0304BQAR"
			(at 0 2.898 270)
			(layer "F.Fab")
			(effects
				(font
					(size 0.7 0.7)
					(thickness 0.15)
				)
				(justify left bottom)
			)
		)
		(property "Datasheet" "https://www.ti.com/lit/ds/symlink/txu0304.pdf?ts=1637748643258&ref_url=https%253A%252F%252Fwww.ti.com%252Fproduct%252FTXU0304"
			(at 0 0 270)
			(layer "F.Fab")
			(hide yes)
			(effects
				(font
					(size 1.27 1.27)
					(thickness 0.15)
				)
			)
		)
		(property "Author" "Antmicro"
			(at -77.034 286.336 0)
			(layer "F.Fab")
			(hide yes)
			(effects
				(font
					(size 1 1)
					(thickness 0.15)
				)
			)
		)
		(property "License" "Apache-2.0"
			(at -77.034 286.336 0)
			(layer "F.Fab")
			(hide yes)
			(effects
				(font
					(size 1 1)
					(thickness 0.15)
				)
			)
		)
		(property "MPN" "TXU0304BQAR"
			(at -77.034 286.336 0)
			(layer "F.Fab")
			(hide yes)
			(effects
				(font
					(size 1 1)
					(thickness 0.15)
				)
			)
		)
		(property "Manufacturer" "Texas Instruments"
			(at -77.034 286.336 0)
			(layer "F.Fab")
			(hide yes)
			(effects
				(font
					(size 1 1)
					(thickness 0.15)
				)
			)
		)
		(sheetname "/Debug FTDI/")
		(sheetfile "debug-ftdi.kicad_sch")
		(attr smd)
		(fp_line
			(start -1.351 1.6)
			(end -0.5 1.6)
			(stroke
				(width 0.15)
				(type solid)
			)
			(layer "F.SilkS")
		)
		(fp_line
			(start -1.351 1.6)
			(end -1.351 1.249)
			(stroke
				(width 0.15)
				(type solid)
			)
			(layer "F.SilkS")
		)
		(fp_line
			(start 0.494 1.6)
			(end 1.35 1.6)
			(stroke
				(width 0.15)
				(type solid)
			)
			(layer "F.SilkS")
		)
		(fp_line
			(start 1.35 1.6)
			(end 1.35 1.249)
			(stroke
				(width 0.15)
				(type solid)
			)
			(layer "F.SilkS")
		)
		(fp_line
			(start -1.351 -1.601)
			(end -0.5 -1.601)
			(stroke
				(width 0.15)
				(type solid)
			)
			(layer "F.SilkS")
		)
		(fp_line
			(start -1.35 -1.601)
			(end -1.35 -1.25)
			(stroke
				(width 0.15)
				(type solid)
			)
			(layer "F.SilkS")
		)
		(fp_line
			(start 1.35 -1.601)
			(end 1.35 -1.25)
			(stroke
				(width 0.15)
				(type solid)
			)
			(layer "F.SilkS")
		)
		(fp_line
			(start 1.35 -1.601)
			(end 0.494 -1.601)
			(stroke
				(width 0.15)
				(type solid)
			)
			(layer "F.SilkS")
		)
		(fp_circle
			(center -0.7 -1.85)
			(end -0.653 -1.85)
			(stroke
				(width 0.15)
				(type solid)
			)
			(fill yes)
			(layer "F.SilkS")
		)
		(fp_rect
			(start -1.85 -2)
			(end 1.8 1.95)
			(stroke
				(width 0.05)
				(type solid)
			)
			(fill no)
			(layer "F.CrtYd")
		)
		(fp_line
			(start -1.25 1.499)
			(end -1.25 -1.25)
			(stroke
				(width 0.15)
				(type solid)
			)
			(layer "F.Fab")
		)
		(fp_line
			(start 1.249 1.499)
			(end -1.25 1.499)
			(stroke
				(width 0.15)
				(type solid)
			)
			(layer "F.Fab")
		)
		(fp_line
			(start -1.25 -1.25)
			(end -1 -1.5)
			(stroke
				(width 0.15)
				(type solid)
			)
			(layer "F.Fab")
		)
		(fp_line
			(start -1 -1.5)
			(end 1.249 -1.5)
			(stroke
				(width 0.15)
				(type solid)
			)
			(layer "F.Fab")
		)
		(fp_line
			(start 1.249 -1.5)
			(end 1.249 1.499)
			(stroke
				(width 0.15)
				(type solid)
			)
			(layer "F.Fab")
		)
		(pad "1" smd oval
			(at -0.25 -1.5 270)
			(size 0.3 0.8)
			(layers "F.Cu" "F.Mask" "F.Paste")
			(net 6 "/Debug FTDI/FTDI_3V3")
			(pinfunction "VCCA")
			(pintype "power_in")
		)
		(pad "2" smd oval
			(at -1.25 -1)
			(size 0.3 0.8)
			(layers "F.Cu" "F.Mask" "F.Paste")
			(net 646 "/Debug FTDI/BDBUS0")
			(pinfunction "A1")
			(pintype "input")
		)
		(pad "3" smd oval
			(at -1.25 -0.5)
			(size 0.3 0.8)
			(layers "F.Cu" "F.Mask" "F.Paste")
			(net 1 "GND")
			(pinfunction "A2")
			(pintype "input")
		)
		(pad "4" smd oval
			(at -1.25 0)
			(size 0.3 0.8)
			(layers "F.Cu" "F.Mask" "F.Paste")
			(net 648 "/Debug FTDI/BDBUS1")
			(pinfunction "A3")
			(pintype "input")
		)
		(pad "5" smd oval
			(at -1.25 0.494)
			(size 0.3 0.8)
			(layers "F.Cu" "F.Mask" "F.Paste")
			(net 650 "/Debug FTDI/BDBUS2")
			(pinfunction "A4Y")
			(pintype "output")
		)
		(pad "6" smd oval
			(at -1.25 0.994)
			(size 0.3 0.8)
			(layers "F.Cu" "F.Mask" "F.Paste")
			(net 718 "unconnected-(U13-NC-Pad6)")
			(pinfunction "NC")
			(pintype "no_connect")
		)
		(pad "7" smd oval
			(at -0.25 1.499 270)
			(size 0.3 0.8)
			(layers "F.Cu" "F.Mask" "F.Paste")
			(net 1 "GND")
			(pinfunction "GND")
			(pintype "passive")
		)
		(pad "8" smd oval
			(at 0.244 1.499 270)
			(size 0.3 0.8)
			(layers "F.Cu" "F.Mask" "F.Paste")
			(net 383 "Net-(U13-OE)")
			(pinfunction "OE")
			(pintype "tri_state")
		)
		(pad "9" smd oval
			(at 1.249 0.994)
			(size 0.3 0.8)
			(layers "F.Cu" "F.Mask" "F.Paste")
			(net 719 "unconnected-(U13-NC-Pad9)")
			(pinfunction "NC")
			(pintype "no_connect")
		)
		(pad "10" smd oval
			(at 1.249 0.494)
			(size 0.3 0.8)
			(layers "F.Cu" "F.Mask" "F.Paste")
			(net 43 "/Debug FTDI/FTDI_SDA_IN")
			(pinfunction "B4")
			(pintype "input")
		)
		(pad "11" smd oval
			(at 1.249 0)
			(size 0.3 0.8)
			(layers "F.Cu" "F.Mask" "F.Paste")
			(net 37 "/Debug FTDI/FTDI_SDA_OUT")
			(pinfunction "B3Y")
			(pintype "output")
		)
		(pad "12" smd oval
			(at 1.249 -0.5)
			(size 0.3 0.8)
			(layers "F.Cu" "F.Mask" "F.Paste")
			(net 720 "unconnected-(U13-B2Y-Pad12)")
			(pinfunction "B2Y")
			(pintype "output+no_connect")
		)
		(pad "13" smd oval
			(at 1.249 -1)
			(size 0.3 0.8)
			(layers "F.Cu" "F.Mask" "F.Paste")
			(net 670 "/Debug FTDI/FTDI_SCL")
			(pinfunction "B1Y")
			(pintype "output")
		)
		(pad "14" smd oval
			(at 0.244 -1.5 270)
			(size 0.3 0.8)
			(layers "F.Cu" "F.Mask" "F.Paste")
			(net 41 "+3V3_AON")
			(pinfunction "VCCB")
			(pintype "power_in")
		)
		(pad "15" smd rect
			(at 0 0 270)
			(size 1 1.5)
			(layers "F.Cu" "F.Mask" "F.Paste")
			(net 1 "GND")
			(pinfunction "GND")
			(pintype "power_in")
		)
	)
	(footprint "antmicro-footprints:C_0805_2012Metric"
		(layer "F.Cu")
		(at 205.395501 184.4605 90)
		(descr "Capacitor SMD 0805")
		(tags "capacitor SMD 0805")
		(property "Reference" "C177"
			(at -2.10551 -1.198678 90)
			(layer "F.SilkS")
			(hide yes)
			(effects
				(font
					(size 0.7 0.7)
					(thickness 0.15)
				)
				(justify left bottom)
			)
		)
		(property "Value" "C_22u_25V_0805"
			(at -2.055717 1.963152 90)
			(layer "F.Fab")
			(effects
				(font
					(size 0.7 0.7)
					(thickness 0.15)
				)
				(justify left bottom)
			)
		)
		(property "Datasheet" "https://product.samsungsem.com/mlcc/CL21A226MAYNNN.do"
			(at 0 0 90)
			(layer "F.Fab")
			(hide yes)
			(effects
				(font
					(size 1.27 1.27)
					(thickness 0.15)
				)
			)
		)
		(property "Author" "Antmicro"
			(at 389.856001 -20.935001 0)
			(layer "F.Fab")
			(hide yes)
			(effects
				(font
					(size 1 1)
					(thickness 0.15)
				)
			)
		)
		(property "Dielectric" ""
			(at 389.856001 -20.935001 0)
			(layer "F.Fab")
			(hide yes)
			(effects
				(font
					(size 1 1)
					(thickness 0.15)
				)
			)
		)
		(property "License" "Apache-2.0"
			(at 389.856001 -20.935001 0)
			(layer "F.Fab")
			(hide yes)
			(effects
				(font
					(size 1 1)
					(thickness 0.15)
				)
			)
		)
		(property "MPN" "CL21A226MAYNNNE"
			(at 389.856001 -20.935001 0)
			(layer "F.Fab")
			(hide yes)
			(effects
				(font
					(size 1 1)
					(thickness 0.15)
				)
			)
		)
		(property "Manufacturer" "Samsung Electro-Mechanics"
			(at 389.856001 -20.935001 0)
			(layer "F.Fab")
			(hide yes)
			(effects
				(font
					(size 1 1)
					(thickness 0.15)
				)
			)
		)
		(property "Val" "22u_25V"
			(at 389.856001 -20.935001 0)
			(layer "F.Fab")
			(hide yes)
			(effects
				(font
					(size 1 1)
					(thickness 0.15)
				)
			)
		)
		(property "Voltage" ""
			(at 389.856001 -20.935001 0)
			(layer "F.Fab")
			(hide yes)
			(effects
				(font
					(size 1 1)
					(thickness 0.15)
				)
			)
		)
		(sheetname "/Supply/")
		(sheetfile "supply.kicad_sch")
		(attr smd)
		(fp_line
			(start -0.3 -0.8)
			(end 0.3 -0.8)
			(stroke
				(width 0.15)
				(type solid)
			)
			(layer "F.SilkS")
		)
		(fp_line
			(start -0.3 0.8)
			(end 0.3 0.8)
			(stroke
				(width 0.15)
				(type solid)
			)
			(layer "F.SilkS")
		)
		(fp_rect
			(start -1.9 -0.93)
			(end 1.9 0.93)
			(stroke
				(width 0.05)
				(type solid)
			)
			(fill no)
			(layer "F.CrtYd")
		)
		(fp_rect
			(start -0.95 -0.675)
			(end 0.95 0.675)
			(stroke
				(width 0.15)
				(type solid)
			)
			(fill no)
			(layer "F.Fab")
		)
		(pad "1" smd rect
			(at -1.05 0 90)
			(size 1.2 1.2)
			(layers "F.Cu" "F.Mask" "F.Paste")
			(net 1 "GND")
			(pintype "passive")
		)
		(pad "2" smd rect
			(at 1.05 0 90)
			(size 1.2 1.2)
			(layers "F.Cu" "F.Mask" "F.Paste")
			(net 38 "VDC")
			(pintype "passive")
		)
	)
	(footprint "antmicro-footprints:C_0402_1005Metric"
		(layer "F.Cu")
		(at 181.55 149.65 180)
		(descr "Capacitor SMD 0402")
		(tags "capacitor SMD 0402")
		(property "Reference" "C220"
			(at 0 -0.699 180)
			(layer "F.SilkS")
			(hide yes)
			(effects
				(font
					(size 0.7 0.7)
					(thickness 0.15)
				)
				(justify left bottom)
			)
		)
		(property "Value" "C_100n_0402"
			(at -1.022927 2.155213 180)
			(layer "F.Fab")
			(effects
				(font
					(size 0.7 0.7)
					(thickness 0.15)
				)
				(justify left bottom)
			)
		)
		(property "Datasheet" "https://www.murata.com/products/productdetail?partno=GRM155R61H104KE14%23"
			(at 0 0 180)
			(layer "F.Fab")
			(hide yes)
			(effects
				(font
					(size 1.27 1.27)
					(thickness 0.15)
				)
			)
		)
		(property "Author" "Antmicro"
			(at 363.1 299.3 0)
			(layer "F.Fab")
			(hide yes)
			(effects
				(font
					(size 1 1)
					(thickness 0.15)
				)
			)
		)
		(property "Dielectric" "X5R"
			(at 363.1 299.3 0)
			(layer "F.Fab")
			(hide yes)
			(effects
				(font
					(size 1 1)
					(thickness 0.15)
				)
			)
		)
		(property "License" "Apache-2.0"
			(at 363.1 299.3 0)
			(layer "F.Fab")
			(hide yes)
			(effects
				(font
					(size 1 1)
					(thickness 0.15)
				)
			)
		)
		(property "MPN" "GRM155R61H104KE14D"
			(at 363.1 299.3 0)
			(layer "F.Fab")
			(hide yes)
			(effects
				(font
					(size 1 1)
					(thickness 0.15)
				)
			)
		)
		(property "Manufacturer" "Murata"
			(at 363.1 299.3 0)
			(layer "F.Fab")
			(hide yes)
			(effects
				(font
					(size 1 1)
					(thickness 0.15)
				)
			)
		)
		(property "Val" "100n"
			(at 363.1 299.3 0)
			(layer "F.Fab")
			(hide yes)
			(effects
				(font
					(size 1 1)
					(thickness 0.15)
				)
			)
		)
		(property "Voltage" "50V"
			(at 363.1 299.3 0)
			(layer "F.Fab")
			(hide yes)
			(effects
				(font
					(size 1 1)
					(thickness 0.15)
				)
			)
		)
		(sheetname "/Supply/")
		(sheetfile "supply.kicad_sch")
		(attr smd)
		(fp_rect
			(start -0.9659 -0.481258)
			(end 0.9649 0.458742)
			(stroke
				(width 0.05)
				(type solid)
			)
			(fill no)
			(layer "F.CrtYd")
		)
		(fp_line
			(start 0.499 0.248)
			(end -0.499 0.248)
			(stroke
				(width 0.15)
				(type solid)
			)
			(layer "F.Fab")
		)
		(fp_line
			(start 0.499 -0.25)
			(end 0.499 0.248)
			(stroke
				(width 0.15)
				(type solid)
			)
			(layer "F.Fab")
		)
		(fp_line
			(start -0.499 0.248)
			(end -0.499 -0.25)
			(stroke
				(width 0.15)
				(type solid)
			)
			(layer "F.Fab")
		)
		(fp_line
			(start -0.499 -0.25)
			(end 0.499 -0.25)
			(stroke
				(width 0.15)
				(type solid)
			)
			(layer "F.Fab")
		)
		(pad "1" smd roundrect
			(at -0.484 0 180)
			(size 0.59 0.64)
			(layers "F.Cu" "F.Mask" "F.Paste")
			(roundrect_rratio 0.25)
			(net 1 "GND")
			(pintype "passive")
		)
		(pad "2" smd roundrect
			(at 0.484 0 180)
			(size 0.59 0.64)
			(layers "F.Cu" "F.Mask" "F.Paste")
			(roundrect_rratio 0.25)
			(net 36 "DAC_VREF")
			(pintype "passive")
		)
	)
	(footprint "antmicro-footprints:R_1206_3216Metric"
		(layer "F.Cu")
		(at 188.675 171.7 180)
		(property "Reference" "R145"
			(at 0.025 1.2 180)
			(layer "F.SilkS")
			(effects
				(font
					(size 0.7 0.7)
					(thickness 0.15)
				)
				(justify left bottom)
			)
		)
		(property "Value" "R_0R01_1206"
			(at -2.422356 2.103591 180)
			(layer "F.Fab")
			(effects
				(font
					(size 0.7 0.7)
					(thickness 0.15)
				)
				(justify left bottom)
			)
		)
		(property "Datasheet" "https://www.yageo.com/upload/media/product/productsearch/datasheet/rchip/PYu-RL_Group_521_RoHS_L_2.pdf"
			(at 0 0 180)
			(layer "F.Fab")
			(hide yes)
			(effects
				(font
					(size 1.27 1.27)
					(thickness 0.15)
				)
			)
		)
		(property "Author" "Antmicro"
			(at 377.35 343.4 0)
			(layer "F.Fab")
			(hide yes)
			(effects
				(font
					(size 1 1)
					(thickness 0.15)
				)
			)
		)
		(property "License" "Apache-2.0"
			(at 377.35 343.4 0)
			(layer "F.Fab")
			(hide yes)
			(effects
				(font
					(size 1 1)
					(thickness 0.15)
				)
			)
		)
		(property "MPN" "RL1206FR-7W0R01L"
			(at 377.35 343.4 0)
			(layer "F.Fab")
			(hide yes)
			(effects
				(font
					(size 1 1)
					(thickness 0.15)
				)
			)
		)
		(property "Manufacturer" "YAGEO"
			(at 377.35 343.4 0)
			(layer "F.Fab")
			(hide yes)
			(effects
				(font
					(size 1 1)
					(thickness 0.15)
				)
			)
		)
		(property "Tolerance" "1%"
			(at 377.35 343.4 0)
			(layer "F.Fab")
			(hide yes)
			(effects
				(font
					(size 1 1)
					(thickness 0.15)
				)
			)
		)
		(property "Val" "0R01"
			(at 377.35 343.4 0)
			(layer "F.Fab")
			(hide yes)
			(effects
				(font
					(size 1 1)
					(thickness 0.15)
				)
			)
		)
		(sheetname "/Supply/")
		(sheetfile "supply.kicad_sch")
		(attr smd)
		(fp_line
			(start 0 0.9)
			(end 0.498 0.9)
			(stroke
				(width 0.15)
				(type solid)
			)
			(layer "F.SilkS")
		)
		(fp_line
			(start 0 0.9)
			(end -0.5 0.9)
			(stroke
				(width 0.15)
				(type solid)
			)
			(layer "F.SilkS")
		)
		(fp_line
			(start 0 -0.902)
			(end 0.498 -0.902)
			(stroke
				(width 0.15)
				(type solid)
			)
			(layer "F.SilkS")
		)
		(fp_line
			(start 0 -0.902)
			(end -0.5 -0.902)
			(stroke
				(width 0.15)
				(type solid)
			)
			(layer "F.SilkS")
		)
		(fp_rect
			(start -2.25 -1.05)
			(end 2.25 1.05)
			(stroke
				(width 0.05)
				(type solid)
			)
			(fill no)
			(layer "F.CrtYd")
		)
		(fp_line
			(start 1.6 -0.802)
			(end 1.6 0.8)
			(stroke
				(width 0.15)
				(type solid)
			)
			(layer "F.Fab")
		)
		(fp_line
			(start -1.601 0.8)
			(end 1.6 0.8)
			(stroke
				(width 0.15)
				(type solid)
			)
			(layer "F.Fab")
		)
		(fp_line
			(start -1.601 -0.802)
			(end 1.6 -0.802)
			(stroke
				(width 0.15)
				(type solid)
			)
			(layer "F.Fab")
		)
		(fp_line
			(start -1.601 -0.802)
			(end -1.601 0.8)
			(stroke
				(width 0.15)
				(type solid)
			)
			(layer "F.Fab")
		)
		(pad "1" smd roundrect
			(at -1.5 0 180)
			(size 1.2 1.8)
			(layers "F.Cu" "F.Mask" "F.Paste")
			(roundrect_rratio 0.15)
			(net 52 "/Supply/3V3_local")
			(pintype "passive")
		)
		(pad "2" smd roundrect
			(at 1.499 0 180)
			(size 1.2 1.8)
			(layers "F.Cu" "F.Mask" "F.Paste")
			(roundrect_rratio 0.15)
			(net 200 "+3V3")
			(pintype "passive")
		)
	)
)
